(kicad_pcb
	(version 20241229)
	(generator "pcbnew")
	(generator_version "9.0")
	(general
		(thickness 1.62)
		(legacy_teardrops no)
	)
	(paper "A4")
	(title_block
		(title "OCuLink to 10GbE adapter")
		(date "2026-02-23")
		(rev "1.1.0")
		(company "Antmicro Ltd")
		(comment 1 "www.antmicro.com")
		(comment 9 "footprints 391-396 of 510")
	)
	(layers
		(0 "F.Cu" signal)
		(4 "In1.Cu" signal)
		(6 "In2.Cu" signal)
		(8 "In3.Cu" signal)
		(10 "In4.Cu" signal)
		(12 "In5.Cu" signal)
		(14 "In6.Cu" signal)
		(2 "B.Cu" signal)
		(9 "F.Adhes" user "F.Adhesive")
		(11 "B.Adhes" user "B.Adhesive")
		(13 "F.Paste" user)
		(15 "B.Paste" user)
		(5 "F.SilkS" user "F.Silkscreen")
		(7 "B.SilkS" user "B.Silkscreen")
		(1 "F.Mask" user)
		(3 "B.Mask" user)
		(17 "Dwgs.User" user "User.Drawings")
		(19 "Cmts.User" user "User.Comments")
		(21 "Eco1.User" user "User.Eco1")
		(23 "Eco2.User" user "User.Eco2")
		(25 "Edge.Cuts" user)
		(27 "Margin" user)
		(31 "F.CrtYd" user "F.Courtyard")
		(29 "B.CrtYd" user "B.Courtyard")
		(35 "F.Fab" user)
		(33 "B.Fab" user)
	)
	(footprint "antmicro-footprints:SOT-416"
		(layer "B.Cu")
		(at 56.25 122.75)
		(descr "SOT-416")
		(tags "SOT-416")
		(property "Reference" "Q7"
			(at 1.169999 0.8 90)
			(layer "B.SilkS")
			(effects
				(font
					(size 0.7 0.7)
					(thickness 0.15)
				)
				(justify right top mirror)
			)
		)
		(property "Value" "DTC014T_SOT-416"
			(at 0 -2.000001 0)
			(layer "B.Fab")
			(hide yes)
			(effects
				(font
					(size 0.7 0.7)
					(thickness 0.15)
				)
				(justify right top mirror)
			)
		)
		(property "Datasheet" "https://www.rohm.com/datasheet?p=DTC014TEB&dist=Mouser&media=referral&source=mouser.com&campaign=Mouser"
			(at 0 0 0)
			(layer "B.Fab")
			(hide yes)
			(effects
				(font
					(size 1.27 1.27)
					(thickness 0.15)
				)
				(justify mirror)
			)
		)
		(property "Description" "Bipolar (BJT) Single Transistor with built-in base resistor, NPN, 50V, 100mA, 150mW, SOT-416FL, Surface Mount"
			(at 0 0 0)
			(layer "B.Fab")
			(hide yes)
			(effects
				(font
					(size 1.27 1.27)
					(thickness 0.15)
				)
				(justify mirror)
			)
		)
		(property "Manufacturer" "ROHM Semiconductor"
			(at 0 0 180)
			(unlocked yes)
			(layer "B.Fab")
			(hide yes)
			(effects
				(font
					(size 1 1)
					(thickness 0.15)
				)
				(justify mirror)
			)
		)
		(property "MPN" "DTC014TEBTL"
			(at 0 0 180)
			(unlocked yes)
			(layer "B.Fab")
			(hide yes)
			(effects
				(font
					(size 1 1)
					(thickness 0.15)
				)
				(justify mirror)
			)
		)
		(property "Author" "Antmicro"
			(at 0 0 180)
			(unlocked yes)
			(layer "B.Fab")
			(hide yes)
			(effects
				(font
					(size 1 1)
					(thickness 0.15)
				)
				(justify mirror)
			)
		)
		(property "License" "Apache-2.0"
			(at 0 0 180)
			(unlocked yes)
			(layer "B.Fab")
			(hide yes)
			(effects
				(font
					(size 1 1)
					(thickness 0.15)
				)
				(justify mirror)
			)
		)
		(sheetname "/Power/")
		(sheetfile "power.kicad_sch")
		(attr smd)
		(fp_line
			(start -0.5 0.15)
			(end -0.5 -0.15)
			(stroke
				(width 0.15)
				(type solid)
			)
			(layer "B.SilkS")
		)
		(fp_line
			(start 0.5 -0.9)
			(end -0.5 -0.9)
			(stroke
				(width 0.15)
				(type solid)
			)
			(layer "B.SilkS")
		)
		(fp_line
			(start 0.5 -0.9)
			(end 0.5 -0.7)
			(stroke
				(width 0.15)
				(type solid)
			)
			(layer "B.SilkS")
		)
		(fp_line
			(start 0.508 0.9)
			(end -0.5 0.9)
			(stroke
				(width 0.15)
				(type solid)
			)
			(layer "B.SilkS")
		)
		(fp_line
			(start 0.508 0.9)
			(end 0.508 0.592)
			(stroke
				(width 0.15)
				(type solid)
			)
			(layer "B.SilkS")
		)
		(fp_rect
			(start -1 1.05)
			(end 1 -1.05)
			(stroke
				(width 0.05)
				(type solid)
			)
			(fill no)
			(layer "B.CrtYd")
		)
		(fp_line
			(start -0.05 0.9)
			(end -0.45 0.5)
			(stroke
				(width 0.15)
				(type solid)
			)
			(layer "B.Fab")
		)
		(fp_rect
			(start 0.45 -0.9)
			(end -0.45 0.9)
			(stroke
				(width 0.15)
				(type solid)
			)
			(fill no)
			(layer "B.Fab")
		)
		(fp_text user "Author: Antmicro"
			(at -1 -4.602 180)
			(layer "B.Fab")
			(effects
				(font
					(size 0.7 0.7)
					(thickness 0.15)
				)
				(justify left bottom mirror)
			)
		)
		(fp_text user "${REFERENCE}"
			(at -1 -3.4 180)
			(layer "B.Fab")
			(effects
				(font
					(size 0.7 0.7)
					(thickness 0.15)
				)
				(justify left bottom mirror)
			)
		)
		(fp_text user "License: Apache-2.0"
			(at -1 -5.802 180)
			(layer "B.Fab")
			(effects
				(font
					(size 0.7 0.7)
					(thickness 0.15)
				)
				(justify left bottom mirror)
			)
		)
		(pad "1" smd rect
			(at -0.652 0.5)
			(size 0.6 0.5)
			(layers "B.Cu" "B.Mask" "B.Paste")
			(net 310 "/Power/+1V88_OUT")
			(pinfunction "B")
			(pintype "input")
		)
		(pad "2" smd rect
			(at -0.652 -0.498)
			(size 0.6 0.5)
			(layers "B.Cu" "B.Mask" "B.Paste")
			(net 28 "GND")
			(pinfunction "E")
			(pintype "passive")
		)
		(pad "3" smd rect
			(at 0.65 0)
			(size 0.6 0.5)
			(layers "B.Cu" "B.Mask" "B.Paste")
			(net 417 "Net-(Q7-C)")
			(pinfunction "C")
			(pintype "passive")
		)
	)
	(footprint "antmicro-footprints:C_0402_1005Metric"
		(layer "B.Cu")
		(at 87.225 98.3 90)
		(descr "Capacitor SMD 0402")
		(tags "capacitor SMD 0402")
		(property "Reference" "C106"
			(at 13.45 0.366228 270)
			(layer "B.SilkS")
			(effects
				(font
					(size 0.7 0.7)
					(thickness 0.15)
				)
				(justify left bottom mirror)
			)
		)
		(property "Value" "C_1u_25V_0402"
			(at -1.022927 -2.155213 270)
			(layer "B.Fab")
			(hide yes)
			(effects
				(font
					(size 0.7 0.7)
					(thickness 0.15)
				)
				(justify left bottom mirror)
			)
		)
		(property "Datasheet" "https://www.murata.com/products/productdetail?partno=GRM155R61E105KE11%23"
			(at 0 0 270)
			(layer "B.Fab")
			(hide yes)
			(effects
				(font
					(size 1.27 1.27)
					(thickness 0.15)
				)
				(justify mirror)
			)
		)
		(property "Description" "SMD Multilayer Ceramic Capacitor, 1 µF, 25 V, 0402 [1005 Metric], ± 10%, X5R, GRM Series"
			(at 0 0 270)
			(layer "B.Fab")
			(hide yes)
			(effects
				(font
					(size 1.27 1.27)
					(thickness 0.15)
				)
				(justify mirror)
			)
		)
		(property "MPN" "GRM155R61E105KE11J"
			(at 0 0 90)
			(unlocked yes)
			(layer "B.Fab")
			(hide yes)
			(effects
				(font
					(size 1 1)
					(thickness 0.15)
				)
				(justify mirror)
			)
		)
		(property "Manufacturer" "Murata"
			(at 0 0 90)
			(unlocked yes)
			(layer "B.Fab")
			(hide yes)
			(effects
				(font
					(size 1 1)
					(thickness 0.15)
				)
				(justify mirror)
			)
		)
		(property "License" "Apache-2.0"
			(at 0 0 90)
			(unlocked yes)
			(layer "B.Fab")
			(hide yes)
			(effects
				(font
					(size 1 1)
					(thickness 0.15)
				)
				(justify mirror)
			)
		)
		(property "Author" "Antmicro"
			(at 0 0 90)
			(unlocked yes)
			(layer "B.Fab")
			(hide yes)
			(effects
				(font
					(size 1 1)
					(thickness 0.15)
				)
				(justify mirror)
			)
		)
		(property "Val" "1u"
			(at 0 0 90)
			(unlocked yes)
			(layer "B.Fab")
			(hide yes)
			(effects
				(font
					(size 1 1)
					(thickness 0.15)
				)
				(justify mirror)
			)
		)
		(property "Voltage" "25V"
			(at 0 0 90)
			(unlocked yes)
			(layer "B.Fab")
			(hide yes)
			(effects
				(font
					(size 1 1)
					(thickness 0.15)
				)
				(justify mirror)
			)
		)
		(property "Dielectric" "X5R"
			(at 0 0 90)
			(unlocked yes)
			(layer "B.Fab")
			(hide yes)
			(effects
				(font
					(size 1 1)
					(thickness 0.15)
				)
				(justify mirror)
			)
		)
		(sheetname "/X710-AT2 power/")
		(sheetfile "x710-at2-power.kicad_sch")
		(attr smd)
		(fp_rect
			(start -0.925 0.47)
			(end 0.925 -0.47)
			(stroke
				(width 0.05)
				(type default)
			)
			(fill no)
			(layer "B.CrtYd")
		)
		(fp_line
			(start 0.504 -0.248)
			(end -0.494 -0.248)
			(stroke
				(width 0.15)
				(type solid)
			)
			(layer "B.Fab")
		)
		(fp_line
			(start -0.494 -0.248)
			(end -0.494 0.25)
			(stroke
				(width 0.15)
				(type solid)
			)
			(layer "B.Fab")
		)
		(fp_line
			(start 0.504 0.25)
			(end 0.504 -0.248)
			(stroke
				(width 0.15)
				(type solid)
			)
			(layer "B.Fab")
		)
		(fp_line
			(start -0.494 0.25)
			(end 0.504 0.25)
			(stroke
				(width 0.15)
				(type solid)
			)
			(layer "B.Fab")
		)
		(pad "1" smd roundrect
			(at -0.48 0 90)
			(size 0.59 0.64)
			(layers "B.Cu" "B.Mask" "B.Paste")
			(roundrect_rratio 0.25)
			(net 28 "GND")
			(pintype "passive")
		)
		(pad "2" smd roundrect
			(at 0.48 0 90)
			(size 0.59 0.64)
			(layers "B.Cu" "B.Mask" "B.Paste")
			(roundrect_rratio 0.25)
			(net 9 "VCCD")
			(pintype "passive")
		)
	)
	(footprint "antmicro-footprints:R_0402_1005Metric"
		(layer "B.Cu")
		(at 74 97.65)
		(descr "Resistor SMD 0402")
		(tags "resistor SMD 0402")
		(property "Reference" "R104"
			(at -0.85 0.45 0)
			(layer "B.SilkS")
			(effects
				(font
					(size 0.7 0.7)
					(thickness 0.15)
				)
				(justify left bottom mirror)
			)
		)
		(property "Value" "R_0R_0402"
			(at -1.011843 -1.772046 0)
			(layer "B.Fab")
			(hide yes)
			(effects
				(font
					(size 0.7 0.7)
					(thickness 0.15)
				)
				(justify right top mirror)
			)
		)
		(property "Datasheet" "https://industrial.panasonic.com/cdbs/www-data/pdf/RDA0000/AOA0000C301.pdf"
			(at 0 0 0)
			(layer "B.Fab")
			(hide yes)
			(effects
				(font
					(size 1.27 1.27)
					(thickness 0.15)
				)
				(justify mirror)
			)
		)
		(property "Description" "SMD Chip Resistor, Jumper, 0 ohm, 100 mW, 0402 [1005 Metric], Thick Film, General Purpose"
			(at 0 0 0)
			(layer "B.Fab")
			(hide yes)
			(effects
				(font
					(size 1.27 1.27)
					(thickness 0.15)
				)
				(justify mirror)
			)
		)
		(property "MPN" "ERJ2GE0R00X"
			(at 0 0 0)
			(unlocked yes)
			(layer "B.Fab")
			(hide yes)
			(effects
				(font
					(size 1 1)
					(thickness 0.15)
				)
				(justify mirror)
			)
		)
		(property "Manufacturer" "Panasonic"
			(at 0 0 0)
			(unlocked yes)
			(layer "B.Fab")
			(hide yes)
			(effects
				(font
					(size 1 1)
					(thickness 0.15)
				)
				(justify mirror)
			)
		)
		(property "License" "Apache-2.0"
			(at 0 0 0)
			(unlocked yes)
			(layer "B.Fab")
			(hide yes)
			(effects
				(font
					(size 1 1)
					(thickness 0.15)
				)
				(justify mirror)
			)
		)
		(property "Author" "Antmicro"
			(at 0 0 0)
			(unlocked yes)
			(layer "B.Fab")
			(hide yes)
			(effects
				(font
					(size 1 1)
					(thickness 0.15)
				)
				(justify mirror)
			)
		)
		(property "Val" "0R"
			(at 0 0 0)
			(unlocked yes)
			(layer "B.Fab")
			(hide yes)
			(effects
				(font
					(size 1 1)
					(thickness 0.15)
				)
				(justify mirror)
			)
		)
		(property "Tolerance" "~"
			(at 0 0 0)
			(unlocked yes)
			(layer "B.Fab")
			(hide yes)
			(effects
				(font
					(size 1 1)
					(thickness 0.15)
				)
				(justify mirror)
			)
		)
		(property "Current" "1A"
			(at 0 0 0)
			(unlocked yes)
			(layer "B.Fab")
			(hide yes)
			(effects
				(font
					(size 1 1)
					(thickness 0.15)
				)
				(justify mirror)
			)
		)
		(sheetname "/X710-AT2 Misc/")
		(sheetfile "x710-at2-mics.kicad_sch")
		(attr smd)
		(fp_rect
			(start -0.925 0.47)
			(end 0.925 -0.47)
			(stroke
				(width 0.05)
				(type default)
			)
			(fill no)
			(layer "B.CrtYd")
		)
		(fp_rect
			(start -0.5 0.25)
			(end 0.5 -0.25)
			(stroke
				(width 0.15)
				(type solid)
			)
			(fill no)
			(layer "B.Fab")
		)
		(pad "1" smd roundrect
			(at -0.48 0)
			(size 0.59 0.64)
			(layers "B.Cu" "B.Mask" "B.Paste")
			(roundrect_rratio 0.25)
			(net 108 "/X710-AT2 Misc/GPIO5_POR_BYPASS")
			(pintype "passive")
		)
		(pad "2" smd roundrect
			(at 0.48 0)
			(size 0.59 0.64)
			(layers "B.Cu" "B.Mask" "B.Paste")
			(roundrect_rratio 0.25)
			(net 47 "/X710-AT2 Misc/POR_BYPASS")
			(pintype "passive")
		)
	)
	(footprint "antmicro-footprints:R_0402_1005Metric"
		(layer "B.Cu")
		(at 106.19 86.644 180)
		(descr "Resistor SMD 0402")
		(tags "resistor SMD 0402")
		(property "Reference" "R118"
			(at -1.89 0.624 0)
			(layer "B.SilkS")
			(effects
				(font
					(size 0.7 0.7)
					(thickness 0.15)
				)
				(justify left bottom mirror)
			)
		)
		(property "Value" "R_100k_0402"
			(at -1.011843 -1.772047 0)
			(layer "B.Fab")
			(hide yes)
			(effects
				(font
					(size 0.7 0.7)
					(thickness 0.15)
				)
				(justify left bottom mirror)
			)
		)
		(property "Datasheet" "https://www.bourns.com/docs/product-datasheets/cr.pdf"
			(at 0 0 0)
			(layer "B.Fab")
			(hide yes)
			(effects
				(font
					(size 1.27 1.27)
					(thickness 0.15)
				)
				(justify mirror)
			)
		)
		(property "Description" "SMD Chip Resistor, 100 kohm, ± 1%, 62.5 mW, 0402 [1005 Metric], Thick Film, General Purpose"
			(at 0 0 0)
			(layer "B.Fab")
			(hide yes)
			(effects
				(font
					(size 1.27 1.27)
					(thickness 0.15)
				)
				(justify mirror)
			)
		)
		(property "MPN" "CR0402-FX-1003GLF"
			(at 0 0 0)
			(unlocked yes)
			(layer "B.Fab")
			(hide yes)
			(effects
				(font
					(size 1 1)
					(thickness 0.15)
				)
				(justify mirror)
			)
		)
		(property "Manufacturer" "Bourns"
			(at 0 0 0)
			(unlocked yes)
			(layer "B.Fab")
			(hide yes)
			(effects
				(font
					(size 1 1)
					(thickness 0.15)
				)
				(justify mirror)
			)
		)
		(property "License" "Apache-2.0"
			(at 0 0 0)
			(unlocked yes)
			(layer "B.Fab")
			(hide yes)
			(effects
				(font
					(size 1 1)
					(thickness 0.15)
				)
				(justify mirror)
			)
		)
		(property "Author" "Antmicro"
			(at 0 0 0)
			(unlocked yes)
			(layer "B.Fab")
			(hide yes)
			(effects
				(font
					(size 1 1)
					(thickness 0.15)
				)
				(justify mirror)
			)
		)
		(property "Val" "100k"
			(at 0 0 0)
			(unlocked yes)
			(layer "B.Fab")
			(hide yes)
			(effects
				(font
					(size 1 1)
					(thickness 0.15)
				)
				(justify mirror)
			)
		)
		(property "Tolerance" "1%"
			(at 0 0 0)
			(unlocked yes)
			(layer "B.Fab")
			(hide yes)
			(effects
				(font
					(size 1 1)
					(thickness 0.15)
				)
				(justify mirror)
			)
		)
		(sheetname "/X710-AT2 PCIe/")
		(sheetfile "x710-at2-pcie.kicad_sch")
		(attr smd exclude_from_pos_files exclude_from_bom dnp)
		(fp_rect
			(start -0.925 0.47)
			(end 0.925 -0.47)
			(stroke
				(width 0.05)
				(type default)
			)
			(fill no)
			(layer "B.CrtYd")
		)
		(fp_rect
			(start -0.5 0.25)
			(end 0.5 -0.25)
			(stroke
				(width 0.15)
				(type solid)
			)
			(fill no)
			(layer "B.Fab")
		)
		(pad "1" smd roundrect
			(at -0.48 0 180)
			(size 0.59 0.64)
			(layers "B.Cu" "B.Mask" "B.Paste")
			(roundrect_rratio 0.25)
			(net 7 "+3V3")
			(pintype "passive")
		)
		(pad "2" smd roundrect
			(at 0.48 0 180)
			(size 0.59 0.64)
			(layers "B.Cu" "B.Mask" "B.Paste")
			(roundrect_rratio 0.25)
			(net 404 "Net-(Y3-EN)")
			(pintype "passive")
		)
	)
	(footprint "antmicro-footprints:R_0402_1005Metric"
		(layer "B.Cu")
		(at 90.225 93.15 180)
		(descr "Resistor SMD 0402")
		(tags "resistor SMD 0402")
		(property "Reference" "R56"
			(at 0.775 -0.55 0)
			(layer "B.SilkS")
			(effects
				(font
					(size 0.7 0.7)
					(thickness 0.15)
				)
				(justify left bottom mirror)
			)
		)
		(property "Value" "R_4k75_0.5%_0402"
			(at -1.011843 -1.772046 0)
			(layer "B.Fab")
			(hide yes)
			(effects
				(font
					(size 0.7 0.7)
					(thickness 0.15)
				)
				(justify left bottom mirror)
			)
		)
		(property "Datasheet" "https://industrial.panasonic.com/cdbs/www-data/pdf/RDQ0000/ast-ind-151033.pdf"
			(at 0 0 0)
			(layer "B.Fab")
			(hide yes)
			(effects
				(font
					(size 1.27 1.27)
					(thickness 0.15)
				)
				(justify mirror)
			)
		)
		(property "Description" "SMD Chip Resistor, 4.75 kohm, ± 0.5%, 100 mW, 0402 [1005 Metric], Thick Film, High Temperature"
			(at 0 0 0)
			(layer "B.Fab")
			(hide yes)
			(effects
				(font
					(size 1.27 1.27)
					(thickness 0.15)
				)
				(justify mirror)
			)
		)
		(property "MPN" "ERJ-H2RD4751X"
			(at 0 0 180)
			(unlocked yes)
			(layer "B.Fab")
			(hide yes)
			(effects
				(font
					(size 1 1)
					(thickness 0.15)
				)
				(justify mirror)
			)
		)
		(property "Manufacturer" "Panasonic"
			(at 0 0 180)
			(unlocked yes)
			(layer "B.Fab")
			(hide yes)
			(effects
				(font
					(size 1 1)
					(thickness 0.15)
				)
				(justify mirror)
			)
		)
		(property "License" "Apache-2.0"
			(at 0 0 180)
			(unlocked yes)
			(layer "B.Fab")
			(hide yes)
			(effects
				(font
					(size 1 1)
					(thickness 0.15)
				)
				(justify mirror)
			)
		)
		(property "Author" "Antmicro"
			(at 0 0 180)
			(unlocked yes)
			(layer "B.Fab")
			(hide yes)
			(effects
				(font
					(size 1 1)
					(thickness 0.15)
				)
				(justify mirror)
			)
		)
		(property "Val" "4k75"
			(at 0 0 180)
			(unlocked yes)
			(layer "B.Fab")
			(hide yes)
			(effects
				(font
					(size 1 1)
					(thickness 0.15)
				)
				(justify mirror)
			)
		)
		(property "Tolerance" "0.5%"
			(at 0 0 180)
			(unlocked yes)
			(layer "B.Fab")
			(hide yes)
			(effects
				(font
					(size 1 1)
					(thickness 0.15)
				)
				(justify mirror)
			)
		)
		(sheetname "/X710-AT2 PCIe/")
		(sheetfile "x710-at2-pcie.kicad_sch")
		(attr smd)
		(fp_rect
			(start -0.925 0.47)
			(end 0.925 -0.47)
			(stroke
				(width 0.05)
				(type default)
			)
			(fill no)
			(layer "B.CrtYd")
		)
		(fp_rect
			(start -0.5 0.25)
			(end 0.5 -0.25)
			(stroke
				(width 0.15)
				(type solid)
			)
			(fill no)
			(layer "B.Fab")
		)
		(pad "1" smd roundrect
			(at -0.48 0 180)
			(size 0.59 0.64)
			(layers "B.Cu" "B.Mask" "B.Paste")
			(roundrect_rratio 0.25)
			(net 3 "/X710-AT2 PCIe/RBIAS")
			(pintype "passive")
		)
		(pad "2" smd roundrect
			(at 0.48 0 180)
			(size 0.59 0.64)
			(layers "B.Cu" "B.Mask" "B.Paste")
			(roundrect_rratio 0.25)
			(net 2 "/X710-AT2 PCIe/RSENSE")
			(pintype "passive")
		)
	)
	(footprint "antmicro-footprints:TP_SMD_0.75mm"
		(layer "B.Cu")
		(at 61.349999 99.500001 180)
		(property "Reference" "TP39"
			(at 0 0.6 0)
			(layer "B.SilkS")
			(hide yes)
			(effects
				(font
					(size 0.7 0.7)
					(thickness 0.15)
				)
				(justify left bottom mirror)
			)
		)
		(property "Value" "TP_0.75mm_SMD"
			(at 0 -1.2 0)
			(layer "B.Fab")
			(hide yes)
			(effects
				(font
					(size 0.7 0.7)
					(thickness 0.15)
				)
				(justify left bottom mirror)
			)
		)
		(property "Description" "SMT test point"
			(at 0 0 0)
			(layer "B.Fab")
			(hide yes)
			(effects
				(font
					(size 1.27 1.27)
					(thickness 0.15)
				)
				(justify mirror)
			)
		)
		(property "MPN" ""
			(at 0 0 0)
			(unlocked yes)
			(layer "B.Fab")
			(hide yes)
			(effects
				(font
					(size 1 1)
					(thickness 0.15)
				)
				(justify mirror)
			)
		)
		(property "Manufacturer" ""
			(at 0 0 0)
			(unlocked yes)
			(layer "B.Fab")
			(hide yes)
			(effects
				(font
					(size 1 1)
					(thickness 0.15)
				)
				(justify mirror)
			)
		)
		(property "Author" "Antmicro"
			(at 0 0 0)
			(unlocked yes)
			(layer "B.Fab")
			(hide yes)
			(effects
				(font
					(size 1 1)
					(thickness 0.15)
				)
				(justify mirror)
			)
		)
		(property "License" "Apache-2.0"
			(at 0 0 0)
			(unlocked yes)
			(layer "B.Fab")
			(hide yes)
			(effects
				(font
					(size 1 1)
					(thickness 0.15)
				)
				(justify mirror)
			)
		)
		(sheetname "/Power/")
		(sheetfile "power.kicad_sch")
		(attr exclude_from_pos_files exclude_from_bom)
		(fp_circle
			(center 0 0)
			(end 0.475 0)
			(stroke
				(width 0.05)
				(type default)
			)
			(fill no)
			(layer "B.CrtYd")
		)
		(pad "1" smd circle
			(at 0 0 180)
			(size 0.75 0.75)
			(layers "B.Cu" "B.Mask")
			(net 310 "/Power/+1V88_OUT")
			(pinfunction "1")
			(pintype "passive")
		)
	)
)
